(kicad_pcb
	(version 20241229)
	(generator "pcbnew")
	(generator_version "9.0")
	(general
		(thickness 1.61)
		(legacy_teardrops no)
	)
	(paper "A3")
	(title_block
		(title "RDIMM DDR5 Tester")
		(date "2026-05-21")
		(rev "2.2.0")
		(company "Antmicro")
		(comment 9 "footprints 633-636 of 796")
	)
	(layers
		(0 "F.Cu" signal)
		(4 "In1.Cu" power)
		(6 "In2.Cu" mixed)
		(8 "In3.Cu" power)
		(10 "In4.Cu" mixed)
		(12 "In5.Cu" power)
		(14 "In6.Cu" mixed)
		(16 "In7.Cu" power)
		(18 "In8.Cu" power)
		(20 "In9.Cu" mixed)
		(22 "In10.Cu" power)
		(2 "B.Cu" signal)
		(9 "F.Adhes" user "F.Adhesive")
		(11 "B.Adhes" user "B.Adhesive")
		(13 "F.Paste" user)
		(15 "B.Paste" user)
		(5 "F.SilkS" user "F.Silkscreen")
		(7 "B.SilkS" user "B.Silkscreen")
		(1 "F.Mask" user)
		(3 "B.Mask" user)
		(17 "Dwgs.User" user "User.Drawings")
		(19 "Cmts.User" user "User.Comments")
		(21 "Eco1.User" user "User.Eco1")
		(23 "Eco2.User" user "User.Eco2")
		(25 "Edge.Cuts" user)
		(27 "Margin" user)
		(31 "F.CrtYd" user "F.Courtyard")
		(29 "B.CrtYd" user "B.Courtyard")
		(35 "F.Fab" user)
		(33 "B.Fab" user)
	)
	(footprint "antmicro-footprints:C_0402_1005Metric_EIA"
		(layer "B.Cu")
		(at 176 159.5 -90)
		(descr "Capacitor SMD 0402 (1005 Metric), square (rectangular) end terminal, IPC_7351 nominal, (Body size source: IPC-SM-782 page 76, https://www.pcb-3d.com/wordpress/wp-content/uploads/ipc-sm-782a_amendment_1_and_2.pdf)")
		(tags "capacitor 0402")
		(property "Reference" "C312"
			(at -0.65 -1.5 90)
			(layer "B.SilkS")
			(effects
				(font
					(size 0.7 0.7)
					(thickness 0.15)
				)
				(justify left bottom mirror)
			)
		)
		(property "Value" "C_100n_0402"
			(at 0 -1.169 90)
			(layer "B.Fab")
			(effects
				(font
					(size 0.7 0.7)
					(thickness 0.15)
				)
				(justify left bottom mirror)
			)
		)
		(property "Datasheet" "https://www.murata.com/products/productdetail?partno=GRM155R61H104KE14%23"
			(at 0 0 270)
			(layer "F.Fab")
			(hide yes)
			(effects
				(font
					(size 1.27 1.27)
					(thickness 0.15)
				)
			)
		)
		(property "MPN" "GRM155R61H104KE14D"
			(at 0 0 270)
			(unlocked yes)
			(layer "B.Fab")
			(hide yes)
			(effects
				(font
					(size 1 1)
					(thickness 0.15)
				)
				(justify mirror)
			)
		)
		(property "Manufacturer" "Murata"
			(at 0 0 270)
			(unlocked yes)
			(layer "B.Fab")
			(hide yes)
			(effects
				(font
					(size 1 1)
					(thickness 0.15)
				)
				(justify mirror)
			)
		)
		(property "License" "Apache-2.0"
			(at 0 0 270)
			(unlocked yes)
			(layer "B.Fab")
			(hide yes)
			(effects
				(font
					(size 1 1)
					(thickness 0.15)
				)
				(justify mirror)
			)
		)
		(property "Author" "Antmicro"
			(at 0 0 270)
			(unlocked yes)
			(layer "B.Fab")
			(hide yes)
			(effects
				(font
					(size 1 1)
					(thickness 0.15)
				)
				(justify mirror)
			)
		)
		(property "Val" "100n"
			(at 0 0 270)
			(unlocked yes)
			(layer "B.Fab")
			(hide yes)
			(effects
				(font
					(size 1 1)
					(thickness 0.15)
				)
				(justify mirror)
			)
		)
		(property "Voltage" "50V"
			(at 0 0 270)
			(unlocked yes)
			(layer "B.Fab")
			(hide yes)
			(effects
				(font
					(size 1 1)
					(thickness 0.15)
				)
				(justify mirror)
			)
		)
		(property "Dielectric" "X5R"
			(at 0 0 270)
			(unlocked yes)
			(layer "B.Fab")
			(hide yes)
			(effects
				(font
					(size 1 1)
					(thickness 0.15)
				)
				(justify mirror)
			)
		)
		(sheetname "/FPGA power/")
		(sheetfile "fpga-power.kicad_sch")
		(attr smd)
		(fp_rect
			(start -0.95 0.45)
			(end 0.95 -0.45)
			(stroke
				(width 0.05)
				(type default)
			)
			(fill no)
			(layer "B.CrtYd")
		)
		(fp_line
			(start -0.5 0.25)
			(end 0.498 0.25)
			(stroke
				(width 0.15)
				(type solid)
			)
			(layer "B.Fab")
		)
		(fp_line
			(start 0.498 0.25)
			(end 0.498 -0.248)
			(stroke
				(width 0.15)
				(type solid)
			)
			(layer "B.Fab")
		)
		(fp_line
			(start -0.5 -0.248)
			(end -0.5 0.25)
			(stroke
				(width 0.15)
				(type solid)
			)
			(layer "B.Fab")
		)
		(fp_line
			(start 0.498 -0.248)
			(end -0.5 -0.248)
			(stroke
				(width 0.15)
				(type solid)
			)
			(layer "B.Fab")
		)
		(fp_text user "${REFERENCE}"
			(at -0.9656 -3.169 90)
			(layer "B.Fab")
			(effects
				(font
					(size 0.7 0.7)
					(thickness 0.15)
				)
				(justify left bottom mirror)
			)
		)
		(fp_text user "Author: Antmicro"
			(at -0.9656 -5.569 90)
			(layer "B.Fab")
			(effects
				(font
					(size 0.7 0.7)
					(thickness 0.15)
				)
				(justify left bottom mirror)
			)
		)
		(fp_text user "License: Apache-2.0"
			(at -0.9656 -4.369 90)
			(layer "B.Fab")
			(effects
				(font
					(size 0.7 0.7)
					(thickness 0.15)
				)
				(justify left bottom mirror)
			)
		)
		(pad "1" smd roundrect
			(at -0.5 0 180)
			(size 0.6 0.6)
			(layers "B.Cu" "B.Mask" "B.Paste")
			(roundrect_rratio 0.25)
			(net 1 "GND")
			(pintype "passive")
		)
		(pad "2" smd roundrect
			(at 0.498 0 270)
			(size 0.6 0.6)
			(layers "B.Cu" "B.Mask" "B.Paste")
			(roundrect_rratio 0.25)
			(net 172 "+1V2_MGTAVTT")
			(pintype "passive")
		)
	)
	(footprint "antmicro-footprints:C_0402_1005Metric_EIA"
		(layer "B.Cu")
		(at 176.5 145)
		(descr "Capacitor SMD 0402 (1005 Metric), square (rectangular) end terminal, IPC_7351 nominal, (Body size source: IPC-SM-782 page 76, https://www.pcb-3d.com/wordpress/wp-content/uploads/ipc-sm-782a_amendment_1_and_2.pdf)")
		(tags "capacitor 0402")
		(property "Reference" "C87"
			(at -1.1 -0.525 0)
			(layer "B.SilkS")
			(effects
				(font
					(size 0.7 0.7)
					(thickness 0.15)
				)
				(justify right bottom mirror)
			)
		)
		(property "Value" "C_10u_10V_0402"
			(at 0 -1.169 0)
			(layer "B.Fab")
			(effects
				(font
					(size 0.7 0.7)
					(thickness 0.15)
				)
				(justify right bottom mirror)
			)
		)
		(property "Datasheet" "https://www.murata.com/products/productdetail?partno=GRM155R61A106ME11%23"
			(at 0 0 0)
			(layer "F.Fab")
			(hide yes)
			(effects
				(font
					(size 1.27 1.27)
					(thickness 0.15)
				)
			)
		)
		(property "MPN" "GRM155R61A106ME11D"
			(at 0 0 0)
			(unlocked yes)
			(layer "B.Fab")
			(hide yes)
			(effects
				(font
					(size 1 1)
					(thickness 0.15)
				)
				(justify mirror)
			)
		)
		(property "Manufacturer" "Murata"
			(at 0 0 0)
			(unlocked yes)
			(layer "B.Fab")
			(hide yes)
			(effects
				(font
					(size 1 1)
					(thickness 0.15)
				)
				(justify mirror)
			)
		)
		(property "License" "Apache-2.0"
			(at 0 0 0)
			(unlocked yes)
			(layer "B.Fab")
			(hide yes)
			(effects
				(font
					(size 1 1)
					(thickness 0.15)
				)
				(justify mirror)
			)
		)
		(property "Author" "Antmicro"
			(at 0 0 0)
			(unlocked yes)
			(layer "B.Fab")
			(hide yes)
			(effects
				(font
					(size 1 1)
					(thickness 0.15)
				)
				(justify mirror)
			)
		)
		(property "Val" "10u"
			(at 0 0 0)
			(unlocked yes)
			(layer "B.Fab")
			(hide yes)
			(effects
				(font
					(size 1 1)
					(thickness 0.15)
				)
				(justify mirror)
			)
		)
		(property "Voltage" "10V"
			(at 0 0 0)
			(unlocked yes)
			(layer "B.Fab")
			(hide yes)
			(effects
				(font
					(size 1 1)
					(thickness 0.15)
				)
				(justify mirror)
			)
		)
		(property "Dielectric" "X5R"
			(at 0 0 0)
			(unlocked yes)
			(layer "B.Fab")
			(hide yes)
			(effects
				(font
					(size 1 1)
					(thickness 0.15)
				)
				(justify mirror)
			)
		)
		(sheetname "/FPGA power/")
		(sheetfile "fpga-power.kicad_sch")
		(attr smd)
		(fp_rect
			(start -0.95 0.45)
			(end 0.95 -0.45)
			(stroke
				(width 0.05)
				(type default)
			)
			(fill no)
			(layer "B.CrtYd")
		)
		(fp_line
			(start -0.5 -0.248)
			(end -0.5 0.25)
			(stroke
				(width 0.15)
				(type solid)
			)
			(layer "B.Fab")
		)
		(fp_line
			(start -0.5 0.25)
			(end 0.498 0.25)
			(stroke
				(width 0.15)
				(type solid)
			)
			(layer "B.Fab")
		)
		(fp_line
			(start 0.498 -0.248)
			(end -0.5 -0.248)
			(stroke
				(width 0.15)
				(type solid)
			)
			(layer "B.Fab")
		)
		(fp_line
			(start 0.498 0.25)
			(end 0.498 -0.248)
			(stroke
				(width 0.15)
				(type solid)
			)
			(layer "B.Fab")
		)
		(fp_text user "License: Apache-2.0"
			(at -0.9656 -4.369 180)
			(layer "B.Fab")
			(effects
				(font
					(size 0.7 0.7)
					(thickness 0.15)
				)
				(justify left bottom mirror)
			)
		)
		(fp_text user "Author: Antmicro"
			(at -0.9656 -5.569 180)
			(layer "B.Fab")
			(effects
				(font
					(size 0.7 0.7)
					(thickness 0.15)
				)
				(justify left bottom mirror)
			)
		)
		(fp_text user "${REFERENCE}"
			(at -0.9656 -3.169 180)
			(layer "B.Fab")
			(effects
				(font
					(size 0.7 0.7)
					(thickness 0.15)
				)
				(justify left bottom mirror)
			)
		)
		(pad "1" smd roundrect
			(at -0.5 0 270)
			(size 0.6 0.6)
			(layers "B.Cu" "B.Mask" "B.Paste")
			(roundrect_rratio 0.25)
			(net 1 "GND")
			(pintype "passive")
		)
		(pad "2" smd roundrect
			(at 0.498 0)
			(size 0.6 0.6)
			(layers "B.Cu" "B.Mask" "B.Paste")
			(roundrect_rratio 0.25)
			(net 797 "+1V8")
			(pintype "passive")
		)
	)
	(footprint "antmicro-footprints:C_0402_1005Metric"
		(layer "B.Cu")
		(at 182.672499 193.2285 90)
		(descr "Capacitor SMD 0402")
		(tags "capacitor SMD 0402")
		(property "Reference" "C257"
			(at 0.994 0.403501 90)
			(layer "B.SilkS")
			(effects
				(font
					(size 0.7 0.7)
					(thickness 0.15)
				)
				(justify right bottom mirror)
			)
		)
		(property "Value" "C_100n_0402"
			(at -1.022927 -2.155213 90)
			(layer "B.Fab")
			(effects
				(font
					(size 0.7 0.7)
					(thickness 0.15)
				)
				(justify right bottom mirror)
			)
		)
		(property "Datasheet" "https://www.murata.com/products/productdetail?partno=GRM155R61H104KE14%23"
			(at 0 0 90)
			(layer "F.Fab")
			(hide yes)
			(effects
				(font
					(size 1.27 1.27)
					(thickness 0.15)
				)
			)
		)
		(property "Manufacturer" "Murata"
			(at 0 0 90)
			(unlocked yes)
			(layer "B.Fab")
			(hide yes)
			(effects
				(font
					(size 1 1)
					(thickness 0.15)
				)
				(justify mirror)
			)
		)
		(property "MPN" "GRM155R61H104KE14D"
			(at 0 0 90)
			(unlocked yes)
			(layer "B.Fab")
			(hide yes)
			(effects
				(font
					(size 1 1)
					(thickness 0.15)
				)
				(justify mirror)
			)
		)
		(property "Val" "100n"
			(at 0 0 90)
			(unlocked yes)
			(layer "B.Fab")
			(hide yes)
			(effects
				(font
					(size 1 1)
					(thickness 0.15)
				)
				(justify mirror)
			)
		)
		(property "License" "Apache-2.0"
			(at 0 0 90)
			(unlocked yes)
			(layer "B.Fab")
			(hide yes)
			(effects
				(font
					(size 1 1)
					(thickness 0.15)
				)
				(justify mirror)
			)
		)
		(property "Author" "Antmicro"
			(at 0 0 90)
			(unlocked yes)
			(layer "B.Fab")
			(hide yes)
			(effects
				(font
					(size 1 1)
					(thickness 0.15)
				)
				(justify mirror)
			)
		)
		(property "Voltage" "50V"
			(at 0 0 90)
			(unlocked yes)
			(layer "B.Fab")
			(hide yes)
			(effects
				(font
					(size 1 1)
					(thickness 0.15)
				)
				(justify mirror)
			)
		)
		(property "Dielectric" "X5R"
			(at 0 0 90)
			(unlocked yes)
			(layer "B.Fab")
			(hide yes)
			(effects
				(font
					(size 1 1)
					(thickness 0.15)
				)
				(justify mirror)
			)
		)
		(sheetname "/FPGA MGT Interface/")
		(sheetfile "fpga-mgt.kicad_sch")
		(attr smd)
		(fp_rect
			(start -0.925 0.47)
			(end 0.925 -0.47)
			(stroke
				(width 0.05)
				(type default)
			)
			(fill no)
			(layer "B.CrtYd")
		)
		(fp_line
			(start 0.504 -0.248)
			(end -0.494 -0.248)
			(stroke
				(width 0.15)
				(type solid)
			)
			(layer "B.Fab")
		)
		(fp_line
			(start -0.494 -0.248)
			(end -0.494 0.25)
			(stroke
				(width 0.15)
				(type solid)
			)
			(layer "B.Fab")
		)
		(fp_line
			(start 0.504 0.25)
			(end 0.504 -0.248)
			(stroke
				(width 0.15)
				(type solid)
			)
			(layer "B.Fab")
		)
		(fp_line
			(start -0.494 0.25)
			(end 0.504 0.25)
			(stroke
				(width 0.15)
				(type solid)
			)
			(layer "B.Fab")
		)
		(fp_text user "Author: Antmicro"
			(at -0.939 -3.399 270)
			(layer "B.Fab")
			(effects
				(font
					(size 0.7 0.7)
					(thickness 0.15)
				)
				(justify left bottom mirror)
			)
		)
		(fp_text user "License: Apache-2.0"
			(at -0.939 -5.799 270)
			(layer "B.Fab")
			(effects
				(font
					(size 0.7 0.7)
					(thickness 0.15)
				)
				(justify left bottom mirror)
			)
		)
		(fp_text user "${REFERENCE}"
			(at -0.939 -4.599 270)
			(layer "B.Fab")
			(effects
				(font
					(size 0.7 0.7)
					(thickness 0.15)
				)
				(justify left bottom mirror)
			)
		)
		(pad "1" smd roundrect
			(at -0.48 0 90)
			(size 0.59 0.64)
			(layers "B.Cu" "B.Mask" "B.Paste")
			(roundrect_rratio 0.25)
			(net 259 "/FPGA MGT Interface/PCIE.TXD4_N")
			(pintype "passive")
		)
		(pad "2" smd roundrect
			(at 0.48 0 90)
			(size 0.59 0.64)
			(layers "B.Cu" "B.Mask" "B.Paste")
			(roundrect_rratio 0.25)
			(net 568 "/FPGA MGT Interface/GTY_224_TX3_N")
			(pintype "passive")
		)
	)
	(footprint "antmicro-footprints:R_0402_1005Metric"
		(layer "B.Cu")
		(at 250.05 183.649 90)
		(descr "Resistor SMD 0402")
		(tags "resistor SMD 0402")
		(property "Reference" "R232"
			(at 1 0.4 90)
			(layer "B.SilkS")
			(effects
				(font
					(size 0.7 0.7)
					(thickness 0.15)
				)
				(justify right bottom mirror)
			)
		)
		(property "Value" "R_47k_0402"
			(at -1.011843 -1.772047 90)
			(layer "B.Fab")
			(effects
				(font
					(size 0.7 0.7)
					(thickness 0.15)
				)
				(justify right bottom mirror)
			)
		)
		(property "Datasheet" "https://www.bourns.com/docs/product-datasheets/cr.pdf"
			(at 0 0 90)
			(layer "F.Fab")
			(hide yes)
			(effects
				(font
					(size 1.27 1.27)
					(thickness 0.15)
				)
			)
		)
		(property "MPN" "CR0402-FX-4702GLF"
			(at 0 0 90)
			(unlocked yes)
			(layer "B.Fab")
			(hide yes)
			(effects
				(font
					(size 1 1)
					(thickness 0.15)
				)
				(justify mirror)
			)
		)
		(property "Manufacturer" "Bourns"
			(at 0 0 90)
			(unlocked yes)
			(layer "B.Fab")
			(hide yes)
			(effects
				(font
					(size 1 1)
					(thickness 0.15)
				)
				(justify mirror)
			)
		)
		(property "License" "Apache-2.0"
			(at 0 0 90)
			(unlocked yes)
			(layer "B.Fab")
			(hide yes)
			(effects
				(font
					(size 1 1)
					(thickness 0.15)
				)
				(justify mirror)
			)
		)
		(property "Author" "Antmicro"
			(at 0 0 90)
			(unlocked yes)
			(layer "B.Fab")
			(hide yes)
			(effects
				(font
					(size 1 1)
					(thickness 0.15)
				)
				(justify mirror)
			)
		)
		(property "Val" "47k"
			(at 0 0 90)
			(unlocked yes)
			(layer "B.Fab")
			(hide yes)
			(effects
				(font
					(size 1 1)
					(thickness 0.15)
				)
				(justify mirror)
			)
		)
		(property "Tolerance" "1%"
			(at 0 0 90)
			(unlocked yes)
			(layer "B.Fab")
			(hide yes)
			(effects
				(font
					(size 1 1)
					(thickness 0.15)
				)
				(justify mirror)
			)
		)
		(sheetname "/I^{2}C + I3C/")
		(sheetfile "i2c.kicad_sch")
		(attr smd)
		(fp_rect
			(start -0.925 0.47)
			(end 0.925 -0.47)
			(stroke
				(width 0.05)
				(type default)
			)
			(fill no)
			(layer "B.CrtYd")
		)
		(fp_rect
			(start -0.5 0.25)
			(end 0.5 -0.25)
			(stroke
				(width 0.15)
				(type solid)
			)
			(fill no)
			(layer "B.Fab")
		)
		(fp_text user "License: Apache-2.0"
			(at -0.95 -5.169 270)
			(layer "B.Fab")
			(effects
				(font
					(size 0.7 0.7)
					(thickness 0.15)
				)
				(justify left bottom mirror)
			)
		)
		(fp_text user "Author: Antmicro"
			(at -0.95 -4.169 270)
			(layer "B.Fab")
			(effects
				(font
					(size 0.7 0.7)
					(thickness 0.15)
				)
				(justify left bottom mirror)
			)
		)
		(fp_text user "${REFERENCE}"
			(at -0.95 -3.168 270)
			(layer "B.Fab")
			(effects
				(font
					(size 0.7 0.7)
					(thickness 0.15)
				)
				(justify left bottom mirror)
			)
		)
		(pad "1" smd roundrect
			(at -0.48 0 90)
			(size 0.59 0.64)
			(layers "B.Cu" "B.Mask" "B.Paste")
			(roundrect_rratio 0.25)
			(net 779 "~{I3C_EXT_PU}")
			(pintype "passive")
		)
		(pad "2" smd roundrect
			(at 0.48 0 90)
			(size 0.59 0.64)
			(layers "B.Cu" "B.Mask" "B.Paste")
			(roundrect_rratio 0.25)
			(net 775 "Net-(Q24-S)")
			(pintype "passive")
		)
	)
)
